# BASEBOARD_FAB2 (Tioga Pass) — schematic netlist excerpt (pin names and nets, part order shuffled) for the footprints in the layout excerpt that follows; sources: Cadence DE-HDL packaged netlist, KiCad conversion of Wiwynn_Tioga_Pass_MB.brd

R25W119  RES  4.75K 1% EMPTY  pkg 0402  page 151 : A = P1V2_AUX_BMC ; B = BMC_M_PAR
R25W183  374R2F-1-GP  1%  pkg SMD-RG  page 255 : \1\ = P3V3_STBY ; \2\ = P0V7_GTL2014_VREF_6
R3P61  RES  2.26K 1.0% CHIP  pkg 0402  page 181 : A = P3V3_STBY ; B = FM_MB_SLOT_ID2

(kicad_pcb
	(version 20260206)
	(generator "pcbnew")
	(generator_version "10.0")
	(general
		(thickness 1.6)
		(legacy_teardrops no)
	)
	(paper "A4")
	(title_block
		(title "Wiwynn_Tioga_Pass_MB.brd")
		(comment 1 "Tioga Pass / footprints 4457-4459 of 4770")
	)
	(layers
		(0 "F.Cu" signal "TOP")
		(4 "In1.Cu" signal "L2GND")
		(6 "In2.Cu" signal "L3")
		(8 "In3.Cu" signal "L4GND")
		(10 "In4.Cu" signal "L5")
		(12 "In5.Cu" signal "L6GND")
		(14 "In6.Cu" signal "L7VCC")
		(16 "In7.Cu" signal "L8VCC")
		(18 "In8.Cu" signal "L9GND")
		(20 "In9.Cu" signal "L10")
		(22 "In10.Cu" signal "L11GND")
		(24 "In11.Cu" signal "L12")
		(26 "In12.Cu" signal "L13GND")
		(2 "B.Cu" signal "BOTTOM")
		(9 "F.Adhes" user "F.Adhesive")
		(11 "B.Adhes" user "B.Adhesive")
		(13 "F.Paste" user "Package Geometry/Pastemask Top")
		(15 "B.Paste" user "Package Geometry/Pastemask Bottom")
		(5 "F.SilkS" user "Ref Des/Silkscreen Top")
		(7 "B.SilkS" user "Ref Des/Silkscreen Bottom")
		(1 "F.Mask" user "Board Geometry/Soldermask Top")
		(3 "B.Mask" user "Board Geometry/Soldermask Bottom")
		(17 "Dwgs.User" user "User.Drawings")
		(19 "Cmts.User" user "User.Comments")
		(21 "Eco1.User" user "User.Eco1")
		(23 "Eco2.User" user "User.Eco2")
		(25 "Edge.Cuts" user "Board Geometry/Outline")
		(27 "Margin" user)
		(31 "F.CrtYd" user "Package Geometry/Place Bound Top")
		(29 "B.CrtYd" user "Package Geometry/Place Bound Bottom")
		(35 "F.Fab" user "Ref Des/Assembly Top")
		(33 "B.Fab" user "Ref Des/Assembly Bottom")
	)
	(footprint ""
		(layer "B.Cu")
		(at 444.1317 -36.738052 180)
		(property "Reference" "R25W119"
			(at 0.8382 -0.67818 180)
			(unlocked yes)
			(layer "B.SilkS")
			(effects
				(font
					(size 0.4064 0.254)
					(thickness 0.1524)
				)
				(justify left mirror)
			)
		)
		(property "Value" ""
			(at 0 0 0)
			(layer "B.Fab")
			(effects
				(font
					(size 1.27 1.27)
				)
				(justify mirror)
			)
		)
		(duplicate_pad_numbers_are_jumpers no)
		(fp_poly
			(pts
				(xy 0.2794 -0.1016) (xy -0.2794 -0.1016) (xy -0.2794 0.9906) (xy 0.2794 0.9906)
			)
			(stroke
				(width 0)
				(type default)
			)
			(fill no)
			(layer "B.CrtYd")
		)
		(fp_line
			(start 0.2794 0.9906)
			(end -0.2794 0.9906)
			(stroke
				(width 0.1)
				(type default)
			)
			(layer "B.Fab")
		)
		(fp_line
			(start 0.2794 -0.1016)
			(end 0.2794 0.9906)
			(stroke
				(width 0.1)
				(type default)
			)
			(layer "B.Fab")
		)
		(fp_line
			(start -0.2794 0.9906)
			(end -0.2794 -0.1016)
			(stroke
				(width 0.1)
				(type default)
			)
			(layer "B.Fab")
		)
		(fp_line
			(start -0.2794 -0.1016)
			(end 0.2794 -0.1016)
			(stroke
				(width 0.1)
				(type default)
			)
			(layer "B.Fab")
		)
		(pad "1" smd rect
			(at 0 0)
			(size 0.508 0.508)
			(layers "B.Cu" "B.Mask" "B.Paste")
			(net "P1V2_AUX_BMC")
		)
		(pad "2" smd rect
			(at 0 0.889)
			(size 0.508 0.508)
			(layers "B.Cu" "B.Mask" "B.Paste")
			(net "BMC_M_PAR")
		)
		(zone
			(layer "B.Cu")
			(hatch none 0.5)
			(connect_pads
				(clearance 0)
			)
			(min_thickness 0.25)
			(keepout
				(tracks not_allowed)
				(vias allowed)
				(pads allowed)
				(copperpour not_allowed)
				(footprints allowed)
			)
			(placement
				(enabled no)
				(sheetname "")
			)
			(fill
				(thermal_gap 0.5)
				(thermal_bridge_width 0.5)
				(island_removal_mode 0)
			)
			(polygon
				(pts
					(xy 443.8777 -37.373052) (xy 444.3857 -37.373052) (xy 444.3857 -36.992052) (xy 443.8777 -36.992052)
				)
			)
		)
		(zone
			(layer "B.Cu")
			(hatch none 0.5)
			(connect_pads
				(clearance 0)
			)
			(min_thickness 0.25)
			(keepout
				(tracks allowed)
				(vias not_allowed)
				(pads allowed)
				(copperpour not_allowed)
				(footprints allowed)
			)
			(placement
				(enabled no)
				(sheetname "")
			)
			(fill
				(thermal_gap 0.5)
				(thermal_bridge_width 0.5)
				(island_removal_mode 0)
			)
			(polygon
				(pts
					(xy 443.8777 -36.992052) (xy 444.3857 -36.992052) (xy 444.3857 -37.373052) (xy 443.8777 -37.373052)
				)
			)
		)
	)
	(footprint ""
		(layer "B.Cu")
		(at 452.5772 -149.0345 180)
		(property "Reference" "R25W183"
			(at 0 0 0)
			(layer "B.SilkS")
			(hide yes)
			(effects
				(font
					(size 1.27 1.27)
				)
				(justify mirror)
			)
		)
		(property "Value" "*"
			(at -0.064008 -4.108196 180)
			(unlocked yes)
			(layer "B.Fab")
			(hide yes)
			(effects
				(font
					(size 1.27 1.016)
					(thickness 0.1524)
				)
				(justify mirror)
			)
		)
		(property "Device Type" "374R2F-1-GP_SMD-RG-374R2F-1-GPA"
			(at -0.064008 -5.632196 180)
			(unlocked yes)
			(layer "B.Fab")
			(hide yes)
			(effects
				(font
					(size 1.27 1.016)
					(thickness 0.1524)
				)
				(justify mirror)
			)
		)
		(duplicate_pad_numbers_are_jumpers no)
		(fp_line
			(start 0.508 -0.9398)
			(end 0.508 0.9398)
			(stroke
				(width 0.1524)
				(type default)
			)
			(layer "B.SilkS")
		)
		(fp_line
			(start -0.508 -0.9398)
			(end 0.508 -0.9398)
			(stroke
				(width 0.1524)
				(type default)
			)
			(layer "B.SilkS")
		)
		(fp_rect
			(start 0.508 0.9398)
			(end -0.508 -0.9398)
			(stroke
				(width 0)
				(type default)
			)
			(fill no)
			(layer "B.CrtYd")
		)
		(fp_rect
			(start 0.508 0.9398)
			(end -0.508 -0.9398)
			(stroke
				(width 0)
				(type default)
			)
			(fill no)
			(layer "B.Fab")
		)
		(pad "1" smd custom
			(at 0 -0.4445)
			(size 0.1397 0.1397)
			(layers "B.Cu" "B.Mask" "B.Paste")
			(net "P3V3_STBY")
			(options
				(clearance outline)
				(anchor circle)
			)
			(primitives
				(gr_poly
					(pts
						(arc
							(start -0.1778 0.2794)
							(mid -0.249642 0.249642)
							(end -0.2794 0.1778)
						)
						(arc
							(start -0.2794 -0.1778)
							(mid -0.249642 -0.249642)
							(end -0.1778 -0.2794)
						)
						(arc
							(start 0.1778 -0.2794)
							(mid 0.249642 -0.249642)
							(end 0.2794 -0.1778)
						)
						(arc
							(start 0.2794 0.1778)
							(mid 0.249642 0.249642)
							(end 0.1778 0.2794)
						)
					)
					(width 0)
					(fill yes)
				)
			)
		)
		(pad "2" smd custom
			(at 0 0.4445)
			(size 0.1397 0.1397)
			(layers "B.Cu" "B.Mask" "B.Paste")
			(net "P0V7_GTL2014_VREF_6")
			(options
				(clearance outline)
				(anchor circle)
			)
			(primitives
				(gr_poly
					(pts
						(arc
							(start -0.1778 0.2794)
							(mid -0.249642 0.249642)
							(end -0.2794 0.1778)
						)
						(arc
							(start -0.2794 -0.1778)
							(mid -0.249642 -0.249642)
							(end -0.1778 -0.2794)
						)
						(arc
							(start 0.1778 -0.2794)
							(mid 0.249642 -0.249642)
							(end 0.2794 -0.1778)
						)
						(arc
							(start 0.2794 0.1778)
							(mid 0.249642 0.249642)
							(end 0.1778 0.2794)
						)
					)
					(width 0)
					(fill yes)
				)
			)
		)
	)
	(footprint ""
		(layer "B.Cu")
		(at 385.318 -87.1601 180)
		(property "Reference" "R3P61"
			(at 0 0 0)
			(layer "B.SilkS")
			(hide yes)
			(effects
				(font
					(size 1.27 1.27)
				)
				(justify mirror)
			)
		)
		(property "Value" ""
			(at 0 0 0)
			(layer "B.Fab")
			(effects
				(font
					(size 1.27 1.27)
				)
				(justify mirror)
			)
		)
		(duplicate_pad_numbers_are_jumpers no)
		(fp_poly
			(pts
				(xy 0.2794 -0.1016) (xy -0.2794 -0.1016) (xy -0.2794 0.9906) (xy 0.2794 0.9906)
			)
			(stroke
				(width 0)
				(type default)
			)
			(fill no)
			(layer "B.CrtYd")
		)
		(fp_line
			(start 0.2794 0.9906)
			(end -0.2794 0.9906)
			(stroke
				(width 0.1)
				(type default)
			)
			(layer "B.Fab")
		)
		(fp_line
			(start 0.2794 -0.1016)
			(end 0.2794 0.9906)
			(stroke
				(width 0.1)
				(type default)
			)
			(layer "B.Fab")
		)
		(fp_line
			(start -0.2794 0.9906)
			(end -0.2794 -0.1016)
			(stroke
				(width 0.1)
				(type default)
			)
			(layer "B.Fab")
		)
		(fp_line
			(start -0.2794 -0.1016)
			(end 0.2794 -0.1016)
			(stroke
				(width 0.1)
				(type default)
			)
			(layer "B.Fab")
		)
		(pad "1" smd rect
			(at 0 0)
			(size 0.508 0.508)
			(layers "B.Cu" "B.Mask" "B.Paste")
			(net "P3V3_STBY")
		)
		(pad "2" smd rect
			(at 0 0.889)
			(size 0.508 0.508)
			(layers "B.Cu" "B.Mask" "B.Paste")
			(net "FM_MB_SLOT_ID2")
		)
		(zone
			(layer "B.Cu")
			(hatch none 0.5)
			(connect_pads
				(clearance 0)
			)
			(min_thickness 0.25)
			(keepout
				(tracks not_allowed)
				(vias allowed)
				(pads allowed)
				(copperpour not_allowed)
				(footprints allowed)
			)
			(placement
				(enabled no)
				(sheetname "")
			)
			(fill
				(thermal_gap 0.5)
				(thermal_bridge_width 0.5)
				(island_removal_mode 0)
			)
			(polygon
				(pts
					(xy 385.064 -87.7951) (xy 385.572 -87.7951) (xy 385.572 -87.4141) (xy 385.064 -87.4141)
				)
			)
		)
		(zone
			(layer "B.Cu")
			(hatch none 0.5)
			(connect_pads
				(clearance 0)
			)
			(min_thickness 0.25)
			(keepout
				(tracks allowed)
				(vias not_allowed)
				(pads allowed)
				(copperpour not_allowed)
				(footprints allowed)
			)
			(placement
				(enabled no)
				(sheetname "")
			)
			(fill
				(thermal_gap 0.5)
				(thermal_bridge_width 0.5)
				(island_removal_mode 0)
			)
			(polygon
				(pts
					(xy 385.064 -87.4141) (xy 385.572 -87.4141) (xy 385.572 -87.7951) (xy 385.064 -87.7951)
				)
			)
		)
	)
)
